# SCM (Grand Teton) — schematic netlist excerpt (pin names and nets, part order shuffled) for the footprints in the layout excerpt that follows; sources: Cadence DE-HDL packaged netlist, KiCad conversion of 12092022_DA0F0TMDCD0_F0T_Management_Board_D_brd_V3_OCP.brd

R30  Q_RES  0 5% CHIP  pkg 0402LF  page 23 : A = CRT_VCC5 ; B = BMC_DDC_BUF_EN
R448  Q_RES  33.2 1% CHIP  pkg 0402LF  page 15 : A = SMB_BMC_ALERT9_N ; B = SMB_BMC_ALERT9_R_N

(kicad_pcb
	(version 20260206)
	(generator "pcbnew")
	(generator_version "10.0")
	(general
		(thickness 1.6)
		(legacy_teardrops no)
	)
	(paper "A4")
	(title_block
		(title "12092022_DA0F0TMDCD0_F0T_Management_Board_D_brd_V3_OCP.brd")
		(comment 1 "Grand Teton / footprints 759-760 of 1440")
	)
	(layers
		(0 "F.Cu" signal "TOP")
		(4 "In1.Cu" signal "GND")
		(6 "In2.Cu" signal "IN1")
		(8 "In3.Cu" signal "GND1")
		(10 "In4.Cu" signal "IN2")
		(12 "In5.Cu" signal "VCC")
		(14 "In6.Cu" signal "VCC1")
		(16 "In7.Cu" signal "IN3")
		(18 "In8.Cu" signal "GND2")
		(20 "In9.Cu" signal "IN4")
		(22 "In10.Cu" signal "GND3")
		(2 "B.Cu" signal "BOTTOM")
		(9 "F.Adhes" user "F.Adhesive")
		(11 "B.Adhes" user "B.Adhesive")
		(13 "F.Paste" user "Package Geometry/Pastemask Top")
		(15 "B.Paste" user "Package Geometry/Pastemask Bottom")
		(5 "F.SilkS" user "Ref Des/Silkscreen Top")
		(7 "B.SilkS" user "Ref Des/Silkscreen Bottom")
		(1 "F.Mask" user "Board Geometry/Soldermask Top")
		(3 "B.Mask" user "Board Geometry/Soldermask Bottom")
		(17 "Dwgs.User" user "User.Drawings")
		(19 "Cmts.User" user "User.Comments")
		(21 "Eco1.User" user "User.Eco1")
		(23 "Eco2.User" user "User.Eco2")
		(25 "Edge.Cuts" user "Board Geometry/Outline")
		(27 "Margin" user)
		(31 "F.CrtYd" user "Package Geometry/Place Bound Top")
		(29 "B.CrtYd" user "Package Geometry/Place Bound Bottom")
		(35 "F.Fab" user "Ref Des/Assembly Top")
		(33 "B.Fab" user "Ref Des/Assembly Bottom")
	)
	(footprint ""
		(layer "B.Cu")
		(at 48.895254 -63.946278 90)
		(property "Reference" "R448"
			(at 0 0 90)
			(layer "B.SilkS")
			(hide yes)
			(effects
				(font
					(size 1.27 1.27)
				)
				(justify mirror)
			)
		)
		(property "Value" ""
			(at 0 0 90)
			(layer "B.Fab")
			(effects
				(font
					(size 1.27 1.27)
				)
				(justify mirror)
			)
		)
		(duplicate_pad_numbers_are_jumpers no)
		(fp_line
			(start 0.7874 -0.4064)
			(end -0.7874 -0.4064)
			(stroke
				(width 0.1524)
				(type default)
			)
			(layer "B.SilkS")
		)
		(fp_line
			(start -0.7874 -0.4064)
			(end -0.7874 0.4064)
			(stroke
				(width 0.1524)
				(type default)
			)
			(layer "B.SilkS")
		)
		(fp_line
			(start 0.7874 0.4064)
			(end 0.7874 -0.4064)
			(stroke
				(width 0.1524)
				(type default)
			)
			(layer "B.SilkS")
		)
		(fp_line
			(start -0.7874 0.4064)
			(end 0.7874 0.4064)
			(stroke
				(width 0.1524)
				(type default)
			)
			(layer "B.SilkS")
		)
		(fp_line
			(start 0.67945 -0.305054)
			(end 0.12065 -0.305054)
			(stroke
				(width 0.1)
				(type default)
			)
			(layer "B.Fab")
		)
		(fp_line
			(start 0.12065 -0.305054)
			(end 0.12065 -0.2794)
			(stroke
				(width 0.1)
				(type default)
			)
			(layer "B.Fab")
		)
		(fp_line
			(start -0.12065 -0.3048)
			(end -0.67945 -0.3048)
			(stroke
				(width 0.1)
				(type default)
			)
			(layer "B.Fab")
		)
		(fp_line
			(start -0.67945 -0.3048)
			(end -0.67945 0.3048)
			(stroke
				(width 0.1)
				(type default)
			)
			(layer "B.Fab")
		)
		(fp_line
			(start 0.12065 -0.2794)
			(end -0.12065 -0.2794)
			(stroke
				(width 0.1)
				(type default)
			)
			(layer "B.Fab")
		)
		(fp_line
			(start -0.12065 -0.2794)
			(end -0.12065 -0.3048)
			(stroke
				(width 0.1)
				(type default)
			)
			(layer "B.Fab")
		)
		(fp_line
			(start 0.12065 0.2794)
			(end 0.12065 0.3048)
			(stroke
				(width 0.1)
				(type default)
			)
			(layer "B.Fab")
		)
		(fp_line
			(start -0.120396 0.2794)
			(end 0.12065 0.2794)
			(stroke
				(width 0.1)
				(type default)
			)
			(layer "B.Fab")
		)
		(fp_line
			(start 0.67945 0.3048)
			(end 0.67945 -0.305054)
			(stroke
				(width 0.1)
				(type default)
			)
			(layer "B.Fab")
		)
		(fp_line
			(start 0.12065 0.3048)
			(end 0.67945 0.3048)
			(stroke
				(width 0.1)
				(type default)
			)
			(layer "B.Fab")
		)
		(fp_line
			(start -0.120396 0.3048)
			(end -0.120396 0.2794)
			(stroke
				(width 0.1)
				(type default)
			)
			(layer "B.Fab")
		)
		(fp_line
			(start -0.67945 0.3048)
			(end -0.120396 0.3048)
			(stroke
				(width 0.1)
				(type default)
			)
			(layer "B.Fab")
		)
		(pad "1" smd circle
			(at 0.40005 0 270)
			(size 0 0)
			(layers "B.Cu" "B.Mask" "B.Paste")
			(net "SMB_BMC_ALERT9_N")
		)
		(pad "2" smd circle
			(at -0.40005 0 270)
			(size 0 0)
			(layers "B.Cu" "B.Mask" "B.Paste")
			(net "SMB_BMC_ALERT9_R_N")
		)
	)
	(footprint ""
		(layer "B.Cu")
		(at 41.5036 -3.6068 90)
		(property "Reference" "R30"
			(at 0 0 90)
			(layer "B.SilkS")
			(hide yes)
			(effects
				(font
					(size 1.27 1.27)
				)
				(justify mirror)
			)
		)
		(property "Value" ""
			(at 0 0 90)
			(layer "B.Fab")
			(effects
				(font
					(size 1.27 1.27)
				)
				(justify mirror)
			)
		)
		(duplicate_pad_numbers_are_jumpers no)
		(fp_line
			(start 0.7874 -0.4064)
			(end -0.7874 -0.4064)
			(stroke
				(width 0.1524)
				(type default)
			)
			(layer "B.SilkS")
		)
		(fp_line
			(start -0.7874 -0.4064)
			(end -0.7874 0.4064)
			(stroke
				(width 0.1524)
				(type default)
			)
			(layer "B.SilkS")
		)
		(fp_line
			(start 0.7874 0.4064)
			(end 0.7874 -0.4064)
			(stroke
				(width 0.1524)
				(type default)
			)
			(layer "B.SilkS")
		)
		(fp_line
			(start -0.7874 0.4064)
			(end 0.7874 0.4064)
			(stroke
				(width 0.1524)
				(type default)
			)
			(layer "B.SilkS")
		)
		(fp_line
			(start 0.67945 -0.305054)
			(end 0.12065 -0.305054)
			(stroke
				(width 0.1)
				(type default)
			)
			(layer "B.Fab")
		)
		(fp_line
			(start 0.12065 -0.305054)
			(end 0.12065 -0.2794)
			(stroke
				(width 0.1)
				(type default)
			)
			(layer "B.Fab")
		)
		(fp_line
			(start -0.12065 -0.3048)
			(end -0.67945 -0.3048)
			(stroke
				(width 0.1)
				(type default)
			)
			(layer "B.Fab")
		)
		(fp_line
			(start -0.67945 -0.3048)
			(end -0.67945 0.3048)
			(stroke
				(width 0.1)
				(type default)
			)
			(layer "B.Fab")
		)
		(fp_line
			(start 0.12065 -0.2794)
			(end -0.12065 -0.2794)
			(stroke
				(width 0.1)
				(type default)
			)
			(layer "B.Fab")
		)
		(fp_line
			(start -0.12065 -0.2794)
			(end -0.12065 -0.3048)
			(stroke
				(width 0.1)
				(type default)
			)
			(layer "B.Fab")
		)
		(fp_line
			(start 0.12065 0.2794)
			(end 0.12065 0.3048)
			(stroke
				(width 0.1)
				(type default)
			)
			(layer "B.Fab")
		)
		(fp_line
			(start -0.120396 0.2794)
			(end 0.12065 0.2794)
			(stroke
				(width 0.1)
				(type default)
			)
			(layer "B.Fab")
		)
		(fp_line
			(start 0.67945 0.3048)
			(end 0.67945 -0.305054)
			(stroke
				(width 0.1)
				(type default)
			)
			(layer "B.Fab")
		)
		(fp_line
			(start 0.12065 0.3048)
			(end 0.67945 0.3048)
			(stroke
				(width 0.1)
				(type default)
			)
			(layer "B.Fab")
		)
		(fp_line
			(start -0.120396 0.3048)
			(end -0.120396 0.2794)
			(stroke
				(width 0.1)
				(type default)
			)
			(layer "B.Fab")
		)
		(fp_line
			(start -0.67945 0.3048)
			(end -0.120396 0.3048)
			(stroke
				(width 0.1)
				(type default)
			)
			(layer "B.Fab")
		)
		(pad "1" smd circle
			(at 0.40005 0 270)
			(size 0 0)
			(layers "B.Cu" "B.Mask" "B.Paste")
			(net "CRT_VCC5")
		)
		(pad "2" smd circle
			(at -0.40005 0 270)
			(size 0 0)
			(layers "B.Cu" "B.Mask" "B.Paste")
			(net "BMC_DDC_BUF_EN")
		)
	)
)
